(kicad_pcb
	(version 20260206)
	(generator "pcbnew")
	(generator_version "10.0")
	(general
		(thickness 1.6)
		(legacy_teardrops no)
	)
	(paper "A4")
	(title_block
		(title "v1-pdb — T6M_PDB_D_0927_0900.brd")
		(comment 1 "Open CloudServer (Microsoft) / footprints 55-65 of 321")
	)
	(layers
		(0 "F.Cu" signal "TOP")
		(4 "In1.Cu" signal "GND")
		(6 "In2.Cu" signal "IN1")
		(8 "In3.Cu" signal "VCC")
		(10 "In4.Cu" signal "VCC1")
		(12 "In5.Cu" signal "IN2")
		(14 "In6.Cu" signal "GND1")
		(2 "B.Cu" signal "BOTTOM")
		(9 "F.Adhes" user "F.Adhesive")
		(11 "B.Adhes" user "B.Adhesive")
		(13 "F.Paste" user "Package Geometry/Pastemask Top")
		(15 "B.Paste" user "Package Geometry/Pastemask Bottom")
		(5 "F.SilkS" user "Ref Des/Silkscreen Top")
		(7 "B.SilkS" user "Ref Des/Silkscreen Bottom")
		(1 "F.Mask" user "Board Geometry/Soldermask Top")
		(3 "B.Mask" user "Board Geometry/Soldermask Bottom")
		(17 "Dwgs.User" user "User.Drawings")
		(19 "Cmts.User" user "User.Comments")
		(21 "Eco1.User" user "User.Eco1")
		(23 "Eco2.User" user "User.Eco2")
		(25 "Edge.Cuts" user "Board Geometry/Outline")
		(27 "Margin" user)
		(31 "F.CrtYd" user "Package Geometry/Place Bound Top")
		(29 "B.CrtYd" user "Package Geometry/Place Bound Bottom")
		(35 "F.Fab" user "Ref Des/Assembly Top")
		(33 "B.Fab" user "Ref Des/Assembly Bottom")
	)
	(footprint ""
		(layer "F.Cu")
		(at 71.405496 -263.260078 90)
		(property "Reference" "C49"
			(at -4.355846 -0.127762 90)
			(unlocked yes)
			(layer "F.SilkS")
			(effects
				(font
					(size 0.7874 0.5842)
					(thickness 0.1524)
				)
				(justify left)
			)
		)
		(property "Value" ""
			(at 0 0 90)
			(layer "F.Fab")
			(effects
				(font
					(size 1.27 1.27)
				)
			)
		)
		(duplicate_pad_numbers_are_jumpers no)
		(fp_line
			(start 0.7874 -0.4064)
			(end 0.7874 0.4064)
			(stroke
				(width 0.1524)
				(type default)
			)
			(layer "F.SilkS")
		)
		(fp_line
			(start -0.7874 -0.4064)
			(end 0.7874 -0.4064)
			(stroke
				(width 0.1524)
				(type default)
			)
			(layer "F.SilkS")
		)
		(fp_line
			(start 0 0.381)
			(end 0 -0.381)
			(stroke
				(width 0.1524)
				(type default)
			)
			(layer "F.SilkS")
		)
		(fp_line
			(start 0.7874 0.4064)
			(end -0.7874 0.4064)
			(stroke
				(width 0.1524)
				(type default)
			)
			(layer "F.SilkS")
		)
		(fp_line
			(start -0.7874 0.4064)
			(end -0.7874 -0.4064)
			(stroke
				(width 0.1524)
				(type default)
			)
			(layer "F.SilkS")
		)
		(fp_poly
			(pts
				(xy -0.5334 0.254) (xy -0.635 0.254) (xy -0.635 0.2286) (xy -0.635 -0.254) (xy -0.5334 -0.254) (xy -0.5334 -0.2794)
				(xy 0.5334 -0.2794) (xy 0.5334 -0.254) (xy 0.635 -0.254) (xy 0.635 0.254) (xy 0.5334 0.254) (xy 0.5334 0.2794)
				(xy -0.508 0.2794) (xy -0.5334 0.2794)
			)
			(stroke
				(width 0)
				(type default)
			)
			(fill no)
			(layer "F.CrtYd")
		)
		(pad "1" smd rect
			(at 0.40005 0 90)
			(size 0.4572 0.508)
			(layers "F.Cu" "F.Mask" "F.Paste")
			(net "P12V")
		)
		(pad "2" smd rect
			(at -0.40005 0 90)
			(size 0.4572 0.508)
			(layers "F.Cu" "F.Mask" "F.Paste")
			(net "GND")
		)
	)
	(footprint ""
		(layer "F.Cu")
		(at 26.068274 -186.752992)
		(property "Reference" "R48"
			(at -3.997198 0.128524 0)
			(unlocked yes)
			(layer "F.SilkS")
			(effects
				(font
					(size 0.7874 0.5842)
					(thickness 0.1524)
				)
				(justify left)
			)
		)
		(property "Value" ""
			(at 0 0 0)
			(layer "F.Fab")
			(effects
				(font
					(size 1.27 1.27)
				)
			)
		)
		(duplicate_pad_numbers_are_jumpers no)
		(fp_line
			(start -0.7874 -0.4064)
			(end 0.7874 -0.4064)
			(stroke
				(width 0.1524)
				(type default)
			)
			(layer "F.SilkS")
		)
		(fp_line
			(start -0.7874 0.4064)
			(end -0.7874 -0.4064)
			(stroke
				(width 0.1524)
				(type default)
			)
			(layer "F.SilkS")
		)
		(fp_line
			(start 0.7874 -0.4064)
			(end 0.7874 0.4064)
			(stroke
				(width 0.1524)
				(type default)
			)
			(layer "F.SilkS")
		)
		(fp_line
			(start 0.7874 0.4064)
			(end -0.7874 0.4064)
			(stroke
				(width 0.1524)
				(type default)
			)
			(layer "F.SilkS")
		)
		(fp_poly
			(pts
				(xy -0.508 0.2794) (xy -0.508 0.2286) (xy -0.635 0.2286) (xy -0.635 -0.254) (xy -0.5334 -0.254)
				(xy -0.5334 -0.2794) (xy 0.5334 -0.2794) (xy 0.5334 -0.254) (xy 0.635 -0.254) (xy 0.635 0.254) (xy 0.5334 0.254)
				(xy 0.5334 0.2794)
			)
			(stroke
				(width 0)
				(type default)
			)
			(fill no)
			(layer "F.CrtYd")
		)
		(pad "1" smd rect
			(at 0.40005 0)
			(size 0.4572 0.508)
			(layers "F.Cu" "F.Mask" "F.Paste")
			(net "PSU3_PS_KILL")
		)
		(pad "2" smd rect
			(at -0.40005 0)
			(size 0.4572 0.508)
			(layers "F.Cu" "F.Mask" "F.Paste")
			(net "GND")
		)
	)
	(footprint ""
		(layer "F.Cu")
		(at 39.821358 -18.414238)
		(property "Reference" "R40"
			(at 1.662938 0.015494 0)
			(unlocked yes)
			(layer "F.SilkS")
			(effects
				(font
					(size 0.7874 0.5842)
					(thickness 0.1524)
				)
				(justify left)
			)
		)
		(property "Value" ""
			(at 0 0 0)
			(layer "F.Fab")
			(effects
				(font
					(size 1.27 1.27)
				)
			)
		)
		(duplicate_pad_numbers_are_jumpers no)
		(fp_line
			(start -0.7874 -0.4064)
			(end 0.7874 -0.4064)
			(stroke
				(width 0.1524)
				(type default)
			)
			(layer "F.SilkS")
		)
		(fp_line
			(start -0.7874 0.4064)
			(end -0.7874 -0.4064)
			(stroke
				(width 0.1524)
				(type default)
			)
			(layer "F.SilkS")
		)
		(fp_line
			(start 0.7874 -0.4064)
			(end 0.7874 0.4064)
			(stroke
				(width 0.1524)
				(type default)
			)
			(layer "F.SilkS")
		)
		(fp_line
			(start 0.7874 0.4064)
			(end -0.7874 0.4064)
			(stroke
				(width 0.1524)
				(type default)
			)
			(layer "F.SilkS")
		)
		(fp_poly
			(pts
				(xy -0.508 0.2794) (xy -0.508 0.2286) (xy -0.635 0.2286) (xy -0.635 -0.254) (xy -0.5334 -0.254)
				(xy -0.5334 -0.2794) (xy 0.5334 -0.2794) (xy 0.5334 -0.254) (xy 0.635 -0.254) (xy 0.635 0.254) (xy 0.5334 0.254)
				(xy 0.5334 0.2794)
			)
			(stroke
				(width 0)
				(type default)
			)
			(fill no)
			(layer "F.CrtYd")
		)
		(pad "1" smd rect
			(at 0.40005 0)
			(size 0.4572 0.508)
			(layers "F.Cu" "F.Mask" "F.Paste")
			(net "GND")
		)
		(pad "2" smd rect
			(at -0.40005 0)
			(size 0.4572 0.508)
			(layers "F.Cu" "F.Mask" "F.Paste")
			(net "P12V_STBY")
		)
	)
	(footprint ""
		(layer "F.Cu")
		(at 27.246072 -20.26412 -90)
		(property "Reference" "R87"
			(at -1.149604 0.97536 90)
			(unlocked yes)
			(layer "F.SilkS")
			(effects
				(font
					(size 0.7874 0.5842)
					(thickness 0.1524)
				)
				(justify left)
			)
		)
		(property "Value" ""
			(at 0 0 270)
			(layer "F.Fab")
			(effects
				(font
					(size 1.27 1.27)
				)
			)
		)
		(duplicate_pad_numbers_are_jumpers no)
		(fp_line
			(start -0.7874 0.4064)
			(end -0.7874 -0.4064)
			(stroke
				(width 0.1524)
				(type default)
			)
			(layer "F.SilkS")
		)
		(fp_line
			(start 0.7874 0.4064)
			(end -0.7874 0.4064)
			(stroke
				(width 0.1524)
				(type default)
			)
			(layer "F.SilkS")
		)
		(fp_line
			(start -0.7874 -0.4064)
			(end 0.7874 -0.4064)
			(stroke
				(width 0.1524)
				(type default)
			)
			(layer "F.SilkS")
		)
		(fp_line
			(start 0.7874 -0.4064)
			(end 0.7874 0.4064)
			(stroke
				(width 0.1524)
				(type default)
			)
			(layer "F.SilkS")
		)
		(fp_poly
			(pts
				(xy -0.508 0.2794) (xy -0.508 0.2286) (xy -0.635 0.2286) (xy -0.635 -0.254) (xy -0.5334 -0.254)
				(xy -0.5334 -0.2794) (xy 0.5334 -0.2794) (xy 0.5334 -0.254) (xy 0.635 -0.254) (xy 0.635 0.254) (xy 0.5334 0.254)
				(xy 0.5334 0.2794)
			)
			(stroke
				(width 0)
				(type default)
			)
			(fill no)
			(layer "F.CrtYd")
		)
		(pad "1" smd rect
			(at 0.40005 0 270)
			(size 0.4572 0.508)
			(layers "F.Cu" "F.Mask" "F.Paste")
			(net "PSU1_REMOTE_N")
		)
		(pad "2" smd rect
			(at -0.40005 0 270)
			(size 0.4572 0.508)
			(layers "F.Cu" "F.Mask" "F.Paste")
			(net "PSU1_REMOTE_R_N")
		)
	)
	(footprint ""
		(layer "F.Cu")
		(at 80.947006 -297.892216 180)
		(property "Reference" "R123"
			(at 1.088644 1.215136 0)
			(unlocked yes)
			(layer "F.SilkS")
			(effects
				(font
					(size 0.7874 0.5842)
					(thickness 0.1524)
				)
				(justify left)
			)
		)
		(property "Value" ""
			(at 0 0 180)
			(layer "F.Fab")
			(effects
				(font
					(size 1.27 1.27)
				)
			)
		)
		(duplicate_pad_numbers_are_jumpers no)
		(fp_line
			(start 0.7874 0.4064)
			(end -0.7874 0.4064)
			(stroke
				(width 0.1524)
				(type default)
			)
			(layer "F.SilkS")
		)
		(fp_line
			(start 0.7874 -0.4064)
			(end 0.7874 0.4064)
			(stroke
				(width 0.1524)
				(type default)
			)
			(layer "F.SilkS")
		)
		(fp_line
			(start -0.7874 0.4064)
			(end -0.7874 -0.4064)
			(stroke
				(width 0.1524)
				(type default)
			)
			(layer "F.SilkS")
		)
		(fp_line
			(start -0.7874 -0.4064)
			(end 0.7874 -0.4064)
			(stroke
				(width 0.1524)
				(type default)
			)
			(layer "F.SilkS")
		)
		(fp_poly
			(pts
				(xy -0.508 0.2794) (xy -0.508 0.2286) (xy -0.635 0.2286) (xy -0.635 -0.254) (xy -0.5334 -0.254)
				(xy -0.5334 -0.2794) (xy 0.5334 -0.2794) (xy 0.5334 -0.254) (xy 0.635 -0.254) (xy 0.635 0.254) (xy 0.5334 0.254)
				(xy 0.5334 0.2794)
			)
			(stroke
				(width 0)
				(type default)
			)
			(fill no)
			(layer "F.CrtYd")
		)
		(pad "1" smd rect
			(at 0.40005 0 180)
			(size 0.4572 0.508)
			(layers "F.Cu" "F.Mask" "F.Paste")
			(net "PSU4_REMOTE_R2_P")
		)
		(pad "2" smd rect
			(at -0.40005 0 180)
			(size 0.4572 0.508)
			(layers "F.Cu" "F.Mask" "F.Paste")
			(net "P12V")
		)
	)
	(footprint ""
		(layer "F.Cu")
		(at 26.103834 -189.265306 180)
		(property "Reference" "R51"
			(at 4.040632 -0.318516 0)
			(unlocked yes)
			(layer "F.SilkS")
			(effects
				(font
					(size 0.7874 0.5842)
					(thickness 0.1524)
				)
				(justify left)
			)
		)
		(property "Value" ""
			(at 0 0 180)
			(layer "F.Fab")
			(effects
				(font
					(size 1.27 1.27)
				)
			)
		)
		(duplicate_pad_numbers_are_jumpers no)
		(fp_line
			(start 0.7874 0.4064)
			(end -0.7874 0.4064)
			(stroke
				(width 0.1524)
				(type default)
			)
			(layer "F.SilkS")
		)
		(fp_line
			(start 0.7874 -0.4064)
			(end 0.7874 0.4064)
			(stroke
				(width 0.1524)
				(type default)
			)
			(layer "F.SilkS")
		)
		(fp_line
			(start -0.7874 0.4064)
			(end -0.7874 -0.4064)
			(stroke
				(width 0.1524)
				(type default)
			)
			(layer "F.SilkS")
		)
		(fp_line
			(start -0.7874 -0.4064)
			(end 0.7874 -0.4064)
			(stroke
				(width 0.1524)
				(type default)
			)
			(layer "F.SilkS")
		)
		(fp_poly
			(pts
				(xy -0.508 0.2794) (xy -0.508 0.2286) (xy -0.635 0.2286) (xy -0.635 -0.254) (xy -0.5334 -0.254)
				(xy -0.5334 -0.2794) (xy 0.5334 -0.2794) (xy 0.5334 -0.254) (xy 0.635 -0.254) (xy 0.635 0.254) (xy 0.5334 0.254)
				(xy 0.5334 0.2794)
			)
			(stroke
				(width 0)
				(type default)
			)
			(fill no)
			(layer "F.CrtYd")
		)
		(pad "1" smd rect
			(at 0.40005 0 180)
			(size 0.4572 0.508)
			(layers "F.Cu" "F.Mask" "F.Paste")
			(net "GND")
		)
		(pad "2" smd rect
			(at -0.40005 0 180)
			(size 0.4572 0.508)
			(layers "F.Cu" "F.Mask" "F.Paste")
			(net "PSU3_PS_ON_N")
		)
	)
	(footprint ""
		(layer "F.Cu")
		(at 27.640026 -461.429862 90)
		(property "Reference" "R133"
			(at -3.59664 -1.369314 90)
			(unlocked yes)
			(layer "F.SilkS")
			(effects
				(font
					(size 0.7874 0.5842)
					(thickness 0.1524)
				)
				(justify left)
			)
		)
		(property "Value" ""
			(at 0 0 90)
			(layer "F.Fab")
			(effects
				(font
					(size 1.27 1.27)
				)
			)
		)
		(duplicate_pad_numbers_are_jumpers no)
		(fp_line
			(start 0.7874 -0.4064)
			(end 0.7874 0.4064)
			(stroke
				(width 0.1524)
				(type default)
			)
			(layer "F.SilkS")
		)
		(fp_line
			(start -0.7874 -0.4064)
			(end 0.7874 -0.4064)
			(stroke
				(width 0.1524)
				(type default)
			)
			(layer "F.SilkS")
		)
		(fp_line
			(start 0.7874 0.4064)
			(end -0.7874 0.4064)
			(stroke
				(width 0.1524)
				(type default)
			)
			(layer "F.SilkS")
		)
		(fp_line
			(start -0.7874 0.4064)
			(end -0.7874 -0.4064)
			(stroke
				(width 0.1524)
				(type default)
			)
			(layer "F.SilkS")
		)
		(fp_poly
			(pts
				(xy -0.508 0.2794) (xy -0.508 0.2286) (xy -0.635 0.2286) (xy -0.635 -0.254) (xy -0.5334 -0.254)
				(xy -0.5334 -0.2794) (xy 0.5334 -0.2794) (xy 0.5334 -0.254) (xy 0.635 -0.254) (xy 0.635 0.254) (xy 0.5334 0.254)
				(xy 0.5334 0.2794)
			)
			(stroke
				(width 0)
				(type default)
			)
			(fill no)
			(layer "F.CrtYd")
		)
		(pad "1" smd rect
			(at 0.40005 0 90)
			(size 0.4572 0.508)
			(layers "F.Cu" "F.Mask" "F.Paste")
			(net "PSU6_REMOTE_N")
		)
		(pad "2" smd rect
			(at -0.40005 0 90)
			(size 0.4572 0.508)
			(layers "F.Cu" "F.Mask" "F.Paste")
			(net "PSU6_REMOTE_R2_N")
		)
	)
	(footprint ""
		(layer "F.Cu")
		(at 69.580252 -131.443476 90)
		(property "Reference" "C27"
			(at -3.811778 -0.029718 90)
			(unlocked yes)
			(layer "F.SilkS")
			(effects
				(font
					(size 0.7874 0.5842)
					(thickness 0.1524)
				)
				(justify left)
			)
		)
		(property "Value" ""
			(at 0 0 90)
			(layer "F.Fab")
			(effects
				(font
					(size 1.27 1.27)
				)
			)
		)
		(duplicate_pad_numbers_are_jumpers no)
		(fp_line
			(start 0.7874 -0.4064)
			(end 0.7874 0.4064)
			(stroke
				(width 0.1524)
				(type default)
			)
			(layer "F.SilkS")
		)
		(fp_line
			(start -0.7874 -0.4064)
			(end 0.7874 -0.4064)
			(stroke
				(width 0.1524)
				(type default)
			)
			(layer "F.SilkS")
		)
		(fp_line
			(start 0 0.381)
			(end 0 -0.381)
			(stroke
				(width 0.1524)
				(type default)
			)
			(layer "F.SilkS")
		)
		(fp_line
			(start 0.7874 0.4064)
			(end -0.7874 0.4064)
			(stroke
				(width 0.1524)
				(type default)
			)
			(layer "F.SilkS")
		)
		(fp_line
			(start -0.7874 0.4064)
			(end -0.7874 -0.4064)
			(stroke
				(width 0.1524)
				(type default)
			)
			(layer "F.SilkS")
		)
		(fp_poly
			(pts
				(xy -0.5334 0.254) (xy -0.635 0.254) (xy -0.635 0.2286) (xy -0.635 -0.254) (xy -0.5334 -0.254) (xy -0.5334 -0.2794)
				(xy 0.5334 -0.2794) (xy 0.5334 -0.254) (xy 0.635 -0.254) (xy 0.635 0.254) (xy 0.5334 0.254) (xy 0.5334 0.2794)
				(xy -0.508 0.2794) (xy -0.5334 0.2794)
			)
			(stroke
				(width 0)
				(type default)
			)
			(fill no)
			(layer "F.CrtYd")
		)
		(pad "1" smd rect
			(at 0.40005 0 90)
			(size 0.4572 0.508)
			(layers "F.Cu" "F.Mask" "F.Paste")
			(net "P12V")
		)
		(pad "2" smd rect
			(at -0.40005 0 90)
			(size 0.4572 0.508)
			(layers "F.Cu" "F.Mask" "F.Paste")
			(net "GND")
		)
	)
	(footprint ""
		(layer "F.Cu")
		(at 39.873936 -22.379432 180)
		(property "Reference" "R1"
			(at -2.42951 0.191262 0)
			(unlocked yes)
			(layer "F.SilkS")
			(effects
				(font
					(size 0.7874 0.5842)
					(thickness 0.1524)
				)
				(justify left)
			)
		)
		(property "Value" ""
			(at 0 0 180)
			(layer "F.Fab")
			(effects
				(font
					(size 1.27 1.27)
				)
			)
		)
		(duplicate_pad_numbers_are_jumpers no)
		(fp_line
			(start 0.7874 0.4064)
			(end -0.7874 0.4064)
			(stroke
				(width 0.1524)
				(type default)
			)
			(layer "F.SilkS")
		)
		(fp_line
			(start 0.7874 -0.4064)
			(end 0.7874 0.4064)
			(stroke
				(width 0.1524)
				(type default)
			)
			(layer "F.SilkS")
		)
		(fp_line
			(start -0.7874 0.4064)
			(end -0.7874 -0.4064)
			(stroke
				(width 0.1524)
				(type default)
			)
			(layer "F.SilkS")
		)
		(fp_line
			(start -0.7874 -0.4064)
			(end 0.7874 -0.4064)
			(stroke
				(width 0.1524)
				(type default)
			)
			(layer "F.SilkS")
		)
		(fp_poly
			(pts
				(xy -0.508 0.2794) (xy -0.508 0.2286) (xy -0.635 0.2286) (xy -0.635 -0.254) (xy -0.5334 -0.254)
				(xy -0.5334 -0.2794) (xy 0.5334 -0.2794) (xy 0.5334 -0.254) (xy 0.635 -0.254) (xy 0.635 0.254) (xy 0.5334 0.254)
				(xy 0.5334 0.2794)
			)
			(stroke
				(width 0)
				(type default)
			)
			(fill no)
			(layer "F.CrtYd")
		)
		(pad "1" smd rect
			(at 0.40005 0 180)
			(size 0.4572 0.508)
			(layers "F.Cu" "F.Mask" "F.Paste")
			(net "PSU1_REMOTE_P")
		)
		(pad "2" smd rect
			(at -0.40005 0 180)
			(size 0.4572 0.508)
			(layers "F.Cu" "F.Mask" "F.Paste")
			(net "P12V")
		)
	)
	(footprint ""
		(layer "F.Cu")
		(at 13.455142 -321.89166 180)
		(property "Reference" "R143"
			(at -1.144016 -0.053848 0)
			(unlocked yes)
			(layer "F.SilkS")
			(effects
				(font
					(size 0.7874 0.5842)
					(thickness 0.1524)
				)
				(justify left)
			)
		)
		(property "Value" ""
			(at 0 0 180)
			(layer "F.Fab")
			(effects
				(font
					(size 1.27 1.27)
				)
			)
		)
		(duplicate_pad_numbers_are_jumpers no)
		(fp_line
			(start 0.7874 0.4064)
			(end -0.7874 0.4064)
			(stroke
				(width 0.1524)
				(type default)
			)
			(layer "F.SilkS")
		)
		(fp_line
			(start 0.7874 -0.4064)
			(end 0.7874 0.4064)
			(stroke
				(width 0.1524)
				(type default)
			)
			(layer "F.SilkS")
		)
		(fp_line
			(start -0.7874 0.4064)
			(end -0.7874 -0.4064)
			(stroke
				(width 0.1524)
				(type default)
			)
			(layer "F.SilkS")
		)
		(fp_line
			(start -0.7874 -0.4064)
			(end 0.7874 -0.4064)
			(stroke
				(width 0.1524)
				(type default)
			)
			(layer "F.SilkS")
		)
		(fp_poly
			(pts
				(xy -0.508 0.2794) (xy -0.508 0.2286) (xy -0.635 0.2286) (xy -0.635 -0.254) (xy -0.5334 -0.254)
				(xy -0.5334 -0.2794) (xy 0.5334 -0.2794) (xy 0.5334 -0.254) (xy 0.635 -0.254) (xy 0.635 0.254) (xy 0.5334 0.254)
				(xy 0.5334 0.2794)
			)
			(stroke
				(width 0)
				(type default)
			)
			(fill no)
			(layer "F.CrtYd")
		)
		(pad "1" smd rect
			(at 0.40005 0 180)
			(size 0.4572 0.508)
			(layers "F.Cu" "F.Mask" "F.Paste")
			(net "FAN2_TACH")
		)
		(pad "2" smd rect
			(at -0.40005 0 180)
			(size 0.4572 0.508)
			(layers "F.Cu" "F.Mask" "F.Paste")
			(net "P12V")
		)
	)
	(footprint ""
		(layer "F.Cu")
		(at 13.36929 -320.828162 180)
		(property "Reference" "R144"
			(at -1.17983 -0.176784 0)
			(unlocked yes)
			(layer "F.SilkS")
			(effects
				(font
					(size 0.7874 0.5842)
					(thickness 0.1524)
				)
				(justify left)
			)
		)
		(property "Value" ""
			(at 0 0 180)
			(layer "F.Fab")
			(effects
				(font
					(size 1.27 1.27)
				)
			)
		)
		(duplicate_pad_numbers_are_jumpers no)
		(fp_line
			(start 0.7874 0.4064)
			(end -0.7874 0.4064)
			(stroke
				(width 0.1524)
				(type default)
			)
			(layer "F.SilkS")
		)
		(fp_line
			(start 0.7874 -0.4064)
			(end 0.7874 0.4064)
			(stroke
				(width 0.1524)
				(type default)
			)
			(layer "F.SilkS")
		)
		(fp_line
			(start -0.7874 0.4064)
			(end -0.7874 -0.4064)
			(stroke
				(width 0.1524)
				(type default)
			)
			(layer "F.SilkS")
		)
		(fp_line
			(start -0.7874 -0.4064)
			(end 0.7874 -0.4064)
			(stroke
				(width 0.1524)
				(type default)
			)
			(layer "F.SilkS")
		)
		(fp_poly
			(pts
				(xy -0.508 0.2794) (xy -0.508 0.2286) (xy -0.635 0.2286) (xy -0.635 -0.254) (xy -0.5334 -0.254)
				(xy -0.5334 -0.2794) (xy 0.5334 -0.2794) (xy 0.5334 -0.254) (xy 0.635 -0.254) (xy 0.635 0.254) (xy 0.5334 0.254)
				(xy 0.5334 0.2794)
			)
			(stroke
				(width 0)
				(type default)
			)
			(fill no)
			(layer "F.CrtYd")
		)
		(pad "1" smd rect
			(at 0.40005 0 180)
			(size 0.4572 0.508)
			(layers "F.Cu" "F.Mask" "F.Paste")
			(net "FAN3_TACH")
		)
		(pad "2" smd rect
			(at -0.40005 0 180)
			(size 0.4572 0.508)
			(layers "F.Cu" "F.Mask" "F.Paste")
			(net "P12V")
		)
	)
)
